(kicad_pcb
	(version 20260206)
	(generator "pcbnew")
	(generator_version "10.0")
	(general
		(thickness 1.6)
		(legacy_teardrops no)
	)
	(paper "A4")
	(title_block
		(title "peb — Lightning_PEB_BRD.brd")
		(comment 1 "Lightning (Wiwynn / Facebook NVMe JBOF) / footprints 31-37 of 2563")
	)
	(layers
		(0 "F.Cu" signal "TOP")
		(4 "In1.Cu" signal "L2GND")
		(6 "In2.Cu" signal "L3")
		(8 "In3.Cu" signal "L4VCC")
		(10 "In4.Cu" signal "L5VCC")
		(12 "In5.Cu" signal "L6")
		(14 "In6.Cu" signal "L7GND")
		(2 "B.Cu" signal "BOTTOM")
		(9 "F.Adhes" user "F.Adhesive")
		(11 "B.Adhes" user "B.Adhesive")
		(13 "F.Paste" user "Package Geometry/Pastemask Top")
		(15 "B.Paste" user "Package Geometry/Pastemask Bottom")
		(5 "F.SilkS" user "Ref Des/Silkscreen Top")
		(7 "B.SilkS" user "Ref Des/Silkscreen Bottom")
		(1 "F.Mask" user "Board Geometry/Soldermask Top")
		(3 "B.Mask" user "Board Geometry/Soldermask Bottom")
		(17 "Dwgs.User" user "User.Drawings")
		(19 "Cmts.User" user "User.Comments")
		(21 "Eco1.User" user "User.Eco1")
		(23 "Eco2.User" user "User.Eco2")
		(25 "Edge.Cuts" user "Board Geometry/Outline")
		(27 "Margin" user)
		(31 "F.CrtYd" user "Package Geometry/Place Bound Top")
		(29 "B.CrtYd" user "Package Geometry/Place Bound Bottom")
		(35 "F.Fab" user "Ref Des/Assembly Top")
		(33 "B.Fab" user "Ref Des/Assembly Bottom")
	)
	(footprint ""
		(layer "F.Cu")
		(at 65.405 -114.106452)
		(property "Reference" "R488"
			(at 0 0 0)
			(layer "F.SilkS")
			(hide yes)
			(effects
				(font
					(size 1.27 1.27)
				)
			)
		)
		(property "Value" "0R2J-2-GP"
			(at 0.064008 -3.993896 0)
			(unlocked yes)
			(layer "F.Fab")
			(hide yes)
			(effects
				(font
					(size 1.016 1.016)
					(thickness 0.1524)
				)
			)
		)
		(property "Device Type" "R402H16"
			(at 0.064008 -5.517896 0)
			(unlocked yes)
			(layer "F.Fab")
			(hide yes)
			(effects
				(font
					(size 1.016 1.016)
					(thickness 0.1524)
				)
			)
		)
		(duplicate_pad_numbers_are_jumpers no)
		(fp_line
			(start -0.508 -0.9398)
			(end -0.508 0.9398)
			(stroke
				(width 0.1524)
				(type default)
			)
			(layer "F.SilkS")
		)
		(fp_line
			(start 0.508 -0.9398)
			(end -0.508 -0.9398)
			(stroke
				(width 0.1524)
				(type default)
			)
			(layer "F.SilkS")
		)
		(fp_rect
			(start -0.508 0.9398)
			(end 0.508 -0.9398)
			(stroke
				(width 0)
				(type default)
			)
			(fill no)
			(layer "F.CrtYd")
		)
		(fp_rect
			(start -0.508 0.9398)
			(end 0.508 -0.9398)
			(stroke
				(width 0)
				(type default)
			)
			(fill no)
			(layer "F.Fab")
		)
		(pad "1" smd custom
			(at 0 -0.4445)
			(size 0.1397 0.1397)
			(layers "F.Cu" "F.Mask" "F.Paste")
			(net "BMC0_SCL11_R")
			(options
				(clearance outline)
				(anchor circle)
			)
			(primitives
				(gr_poly
					(pts
						(arc
							(start -0.1778 -0.2794)
							(mid -0.249642 -0.249642)
							(end -0.2794 -0.1778)
						)
						(arc
							(start -0.2794 0.1778)
							(mid -0.249642 0.249642)
							(end -0.1778 0.2794)
						)
						(arc
							(start 0.1778 0.2794)
							(mid 0.249642 0.249642)
							(end 0.2794 0.1778)
						)
						(arc
							(start 0.2794 -0.1778)
							(mid 0.249642 -0.249642)
							(end 0.1778 -0.2794)
						)
					)
					(width 0)
					(fill yes)
				)
			)
		)
		(pad "2" smd custom
			(at 0 0.4445)
			(size 0.1397 0.1397)
			(layers "F.Cu" "F.Mask" "F.Paste")
			(net "BMC_I2C11_MINI5_SCL_S")
			(options
				(clearance outline)
				(anchor circle)
			)
			(primitives
				(gr_poly
					(pts
						(arc
							(start -0.1778 -0.2794)
							(mid -0.249642 -0.249642)
							(end -0.2794 -0.1778)
						)
						(arc
							(start -0.2794 0.1778)
							(mid -0.249642 0.249642)
							(end -0.1778 0.2794)
						)
						(arc
							(start 0.1778 0.2794)
							(mid 0.249642 0.249642)
							(end 0.2794 0.1778)
						)
						(arc
							(start 0.2794 -0.1778)
							(mid 0.249642 -0.249642)
							(end 0.1778 -0.2794)
						)
					)
					(width 0)
					(fill yes)
				)
			)
		)
	)
	(footprint ""
		(layer "F.Cu")
		(at 54.792118 -212.420454 180)
		(property "Reference" "C361"
			(at 0 0 180)
			(layer "F.SilkS")
			(hide yes)
			(effects
				(font
					(size 1.27 1.27)
				)
			)
		)
		(property "Value" "SCD22U10V2KX-1GP"
			(at 1.1811 -2.7051 180)
			(unlocked yes)
			(layer "F.Fab")
			(hide yes)
			(effects
				(font
					(size 1.016 1.016)
					(thickness 0.1524)
				)
			)
		)
		(property "Device Type" "C402H22"
			(at 1.1811 -4.2291 180)
			(unlocked yes)
			(layer "F.Fab")
			(hide yes)
			(effects
				(font
					(size 1.016 1.016)
					(thickness 0.1524)
				)
			)
		)
		(duplicate_pad_numbers_are_jumpers no)
		(fp_rect
			(start -0.4318 0.9525)
			(end 0.4318 -0.9525)
			(stroke
				(width 0)
				(type default)
			)
			(fill no)
			(layer "F.CrtYd")
		)
		(fp_rect
			(start -0.4318 0.9525)
			(end 0.4318 -0.9525)
			(stroke
				(width 0)
				(type default)
			)
			(fill no)
			(layer "F.Fab")
		)
		(pad "1" smd custom
			(at 0 -0.4445 180)
			(size 0.1524 0.1524)
			(layers "F.Cu" "F.Mask" "F.Paste")
			(net "PCIE_TX_CAP_P73")
			(options
				(clearance outline)
				(anchor circle)
			)
			(primitives
				(gr_poly
					(pts
						(arc
							(start 0.3048 -0.2032)
							(mid 0.275042 -0.275042)
							(end 0.2032 -0.3048)
						)
						(arc
							(start -0.2032 -0.3048)
							(mid -0.275042 -0.275042)
							(end -0.3048 -0.2032)
						)
						(arc
							(start -0.3048 0.2032)
							(mid -0.275042 0.275042)
							(end -0.2032 0.3048)
						)
						(arc
							(start 0.2032 0.3048)
							(mid 0.275042 0.275042)
							(end 0.3048 0.2032)
						)
					)
					(width 0)
					(fill yes)
				)
			)
		)
		(pad "2" smd custom
			(at 0 0.4445 180)
			(size 0.1524 0.1524)
			(layers "F.Cu" "F.Mask" "F.Paste")
			(net "PCIE_TX_P73")
			(options
				(clearance outline)
				(anchor circle)
			)
			(primitives
				(gr_poly
					(pts
						(arc
							(start 0.3048 -0.2032)
							(mid 0.275042 -0.275042)
							(end 0.2032 -0.3048)
						)
						(arc
							(start -0.2032 -0.3048)
							(mid -0.275042 -0.275042)
							(end -0.3048 -0.2032)
						)
						(arc
							(start -0.3048 0.2032)
							(mid -0.275042 0.275042)
							(end -0.2032 0.3048)
						)
						(arc
							(start 0.2032 0.3048)
							(mid 0.275042 0.275042)
							(end 0.3048 0.2032)
						)
					)
					(width 0)
					(fill yes)
				)
			)
		)
	)
	(footprint ""
		(layer "F.Cu")
		(at 331.216 -9.652)
		(property "Reference" "SR712"
			(at 0 0 0)
			(layer "F.SilkS")
			(hide yes)
			(effects
				(font
					(size 1.27 1.27)
				)
			)
		)
		(property "Value" "150R2F-1-GP"
			(at 0.064008 -3.993896 0)
			(unlocked yes)
			(layer "F.Fab")
			(hide yes)
			(effects
				(font
					(size 1.016 1.016)
					(thickness 0.1524)
				)
			)
		)
		(property "Device Type" "R402H16"
			(at 0.064008 -5.517896 0)
			(unlocked yes)
			(layer "F.Fab")
			(hide yes)
			(effects
				(font
					(size 1.016 1.016)
					(thickness 0.1524)
				)
			)
		)
		(duplicate_pad_numbers_are_jumpers no)
		(fp_line
			(start -0.508 -0.9398)
			(end -0.508 0.9398)
			(stroke
				(width 0.1524)
				(type default)
			)
			(layer "F.SilkS")
		)
		(fp_line
			(start 0.508 -0.9398)
			(end -0.508 -0.9398)
			(stroke
				(width 0.1524)
				(type default)
			)
			(layer "F.SilkS")
		)
		(fp_rect
			(start -0.508 0.9398)
			(end 0.508 -0.9398)
			(stroke
				(width 0)
				(type default)
			)
			(fill no)
			(layer "F.CrtYd")
		)
		(fp_rect
			(start -0.508 0.9398)
			(end 0.508 -0.9398)
			(stroke
				(width 0)
				(type default)
			)
			(fill no)
			(layer "F.Fab")
		)
		(pad "1" smd custom
			(at 0 -0.4445)
			(size 0.1397 0.1397)
			(layers "F.Cu" "F.Mask" "F.Paste")
			(net "P3V3_STBY")
			(options
				(clearance outline)
				(anchor circle)
			)
			(primitives
				(gr_poly
					(pts
						(arc
							(start -0.1778 -0.2794)
							(mid -0.249642 -0.249642)
							(end -0.2794 -0.1778)
						)
						(arc
							(start -0.2794 0.1778)
							(mid -0.249642 0.249642)
							(end -0.1778 0.2794)
						)
						(arc
							(start 0.1778 0.2794)
							(mid 0.249642 0.249642)
							(end 0.2794 0.1778)
						)
						(arc
							(start 0.2794 -0.1778)
							(mid 0.249642 -0.249642)
							(end 0.1778 -0.2794)
						)
					)
					(width 0)
					(fill yes)
				)
			)
		)
		(pad "2" smd custom
			(at 0 0.4445)
			(size 0.1397 0.1397)
			(layers "F.Cu" "F.Mask" "F.Paste")
			(net "LED_R_7")
			(options
				(clearance outline)
				(anchor circle)
			)
			(primitives
				(gr_poly
					(pts
						(arc
							(start -0.1778 -0.2794)
							(mid -0.249642 -0.249642)
							(end -0.2794 -0.1778)
						)
						(arc
							(start -0.2794 0.1778)
							(mid -0.249642 0.249642)
							(end -0.1778 0.2794)
						)
						(arc
							(start 0.1778 0.2794)
							(mid 0.249642 0.249642)
							(end 0.2794 0.1778)
						)
						(arc
							(start 0.2794 -0.1778)
							(mid 0.249642 -0.249642)
							(end 0.1778 -0.2794)
						)
					)
					(width 0)
					(fill yes)
				)
			)
		)
	)
	(footprint ""
		(layer "F.Cu")
		(at 229.997 -84.582 180)
		(property "Reference" "C328"
			(at 0 0 180)
			(layer "F.SilkS")
			(hide yes)
			(effects
				(font
					(size 1.27 1.27)
				)
			)
		)
		(property "Value" "SCD1U16V2KX-3GP"
			(at 1.1811 -2.7051 180)
			(unlocked yes)
			(layer "F.Fab")
			(hide yes)
			(effects
				(font
					(size 1.016 1.016)
					(thickness 0.1524)
				)
			)
		)
		(property "Device Type" "C402H22"
			(at 1.1811 -4.2291 180)
			(unlocked yes)
			(layer "F.Fab")
			(hide yes)
			(effects
				(font
					(size 1.016 1.016)
					(thickness 0.1524)
				)
			)
		)
		(duplicate_pad_numbers_are_jumpers no)
		(fp_rect
			(start -0.4318 0.9525)
			(end 0.4318 -0.9525)
			(stroke
				(width 0)
				(type default)
			)
			(fill no)
			(layer "F.CrtYd")
		)
		(fp_rect
			(start -0.4318 0.9525)
			(end 0.4318 -0.9525)
			(stroke
				(width 0)
				(type default)
			)
			(fill no)
			(layer "F.Fab")
		)
		(pad "1" smd custom
			(at 0 -0.4445 180)
			(size 0.1524 0.1524)
			(layers "F.Cu" "F.Mask" "F.Paste")
			(net "P3V3_STBY")
			(options
				(clearance outline)
				(anchor circle)
			)
			(primitives
				(gr_poly
					(pts
						(arc
							(start 0.3048 -0.2032)
							(mid 0.275042 -0.275042)
							(end 0.2032 -0.3048)
						)
						(arc
							(start -0.2032 -0.3048)
							(mid -0.275042 -0.275042)
							(end -0.3048 -0.2032)
						)
						(arc
							(start -0.3048 0.2032)
							(mid -0.275042 0.275042)
							(end -0.2032 0.3048)
						)
						(arc
							(start 0.2032 0.3048)
							(mid 0.275042 0.275042)
							(end 0.3048 0.2032)
						)
					)
					(width 0)
					(fill yes)
				)
			)
		)
		(pad "2" smd custom
			(at 0 0.4445 180)
			(size 0.1524 0.1524)
			(layers "F.Cu" "F.Mask" "F.Paste")
			(net "GND")
			(options
				(clearance outline)
				(anchor circle)
			)
			(primitives
				(gr_poly
					(pts
						(arc
							(start 0.3048 -0.2032)
							(mid 0.275042 -0.275042)
							(end 0.2032 -0.3048)
						)
						(arc
							(start -0.2032 -0.3048)
							(mid -0.275042 -0.275042)
							(end -0.3048 -0.2032)
						)
						(arc
							(start -0.3048 0.2032)
							(mid -0.275042 0.275042)
							(end -0.2032 0.3048)
						)
						(arc
							(start 0.2032 0.3048)
							(mid 0.275042 0.275042)
							(end 0.3048 0.2032)
						)
					)
					(width 0)
					(fill yes)
				)
			)
		)
	)
	(footprint ""
		(layer "F.Cu")
		(at 24.218646 -121.219214 90)
		(property "Reference" "R541"
			(at 0 0 90)
			(layer "F.SilkS")
			(hide yes)
			(effects
				(font
					(size 1.27 1.27)
				)
			)
		)
		(property "Value" "0R2J-2-GP"
			(at 0.064008 -3.993896 90)
			(unlocked yes)
			(layer "F.Fab")
			(hide yes)
			(effects
				(font
					(size 1.016 1.016)
					(thickness 0.1524)
				)
			)
		)
		(property "Device Type" "R402H16"
			(at 0.064008 -5.517896 90)
			(unlocked yes)
			(layer "F.Fab")
			(hide yes)
			(effects
				(font
					(size 1.016 1.016)
					(thickness 0.1524)
				)
			)
		)
		(duplicate_pad_numbers_are_jumpers no)
		(fp_line
			(start 0.508 -0.9398)
			(end -0.508 -0.9398)
			(stroke
				(width 0.1524)
				(type default)
			)
			(layer "F.SilkS")
		)
		(fp_line
			(start -0.508 -0.9398)
			(end -0.508 0.9398)
			(stroke
				(width 0.1524)
				(type default)
			)
			(layer "F.SilkS")
		)
		(fp_rect
			(start -0.508 0.9398)
			(end 0.508 -0.9398)
			(stroke
				(width 0)
				(type default)
			)
			(fill no)
			(layer "F.CrtYd")
		)
		(fp_rect
			(start -0.508 0.9398)
			(end 0.508 -0.9398)
			(stroke
				(width 0)
				(type default)
			)
			(fill no)
			(layer "F.Fab")
		)
		(pad "1" smd custom
			(at 0 -0.4445 90)
			(size 0.1397 0.1397)
			(layers "F.Cu" "F.Mask" "F.Paste")
			(net "P0V9_E_PG")
			(options
				(clearance outline)
				(anchor circle)
			)
			(primitives
				(gr_poly
					(pts
						(arc
							(start -0.1778 -0.2794)
							(mid -0.249642 -0.249642)
							(end -0.2794 -0.1778)
						)
						(arc
							(start -0.2794 0.1778)
							(mid -0.249642 0.249642)
							(end -0.1778 0.2794)
						)
						(arc
							(start 0.1778 0.2794)
							(mid 0.249642 0.249642)
							(end 0.2794 0.1778)
						)
						(arc
							(start 0.2794 -0.1778)
							(mid 0.249642 -0.249642)
							(end 0.1778 -0.2794)
						)
					)
					(width 0)
					(fill yes)
				)
			)
		)
		(pad "2" smd custom
			(at 0 0.4445 90)
			(size 0.1397 0.1397)
			(layers "F.Cu" "F.Mask" "F.Paste")
			(net "PWGD_P0V9_E_PG_R")
			(options
				(clearance outline)
				(anchor circle)
			)
			(primitives
				(gr_poly
					(pts
						(arc
							(start -0.1778 -0.2794)
							(mid -0.249642 -0.249642)
							(end -0.2794 -0.1778)
						)
						(arc
							(start -0.2794 0.1778)
							(mid -0.249642 0.249642)
							(end -0.1778 0.2794)
						)
						(arc
							(start 0.1778 0.2794)
							(mid 0.249642 0.249642)
							(end 0.2794 0.1778)
						)
						(arc
							(start 0.2794 -0.1778)
							(mid 0.249642 -0.249642)
							(end 0.1778 -0.2794)
						)
					)
					(width 0)
					(fill yes)
				)
			)
		)
	)
	(footprint ""
		(layer "F.Cu")
		(at 64.389 -133.985)
		(property "Reference" "R5762"
			(at 0 0 0)
			(layer "F.SilkS")
			(hide yes)
			(effects
				(font
					(size 1.27 1.27)
				)
			)
		)
		(property "Value" "1KR2F-3-GP"
			(at 0.064008 -3.993896 0)
			(unlocked yes)
			(layer "F.Fab")
			(hide yes)
			(effects
				(font
					(size 1.016 1.016)
					(thickness 0.1524)
				)
			)
		)
		(property "Device Type" "R402H16"
			(at 0.064008 -5.517896 0)
			(unlocked yes)
			(layer "F.Fab")
			(hide yes)
			(effects
				(font
					(size 1.016 1.016)
					(thickness 0.1524)
				)
			)
		)
		(duplicate_pad_numbers_are_jumpers no)
		(fp_line
			(start -0.508 -0.9398)
			(end -0.508 0.9398)
			(stroke
				(width 0.1524)
				(type default)
			)
			(layer "F.SilkS")
		)
		(fp_line
			(start 0.508 -0.9398)
			(end -0.508 -0.9398)
			(stroke
				(width 0.1524)
				(type default)
			)
			(layer "F.SilkS")
		)
		(fp_rect
			(start -0.508 0.9398)
			(end 0.508 -0.9398)
			(stroke
				(width 0)
				(type default)
			)
			(fill no)
			(layer "F.CrtYd")
		)
		(fp_rect
			(start -0.508 0.9398)
			(end 0.508 -0.9398)
			(stroke
				(width 0)
				(type default)
			)
			(fill no)
			(layer "F.Fab")
		)
		(pad "1" smd custom
			(at 0 -0.4445)
			(size 0.1397 0.1397)
			(layers "F.Cu" "F.Mask" "F.Paste")
			(net "ADC_P0V9")
			(options
				(clearance outline)
				(anchor circle)
			)
			(primitives
				(gr_poly
					(pts
						(arc
							(start -0.1778 -0.2794)
							(mid -0.249642 -0.249642)
							(end -0.2794 -0.1778)
						)
						(arc
							(start -0.2794 0.1778)
							(mid -0.249642 0.249642)
							(end -0.1778 0.2794)
						)
						(arc
							(start 0.1778 0.2794)
							(mid 0.249642 0.249642)
							(end 0.2794 0.1778)
						)
						(arc
							(start 0.2794 -0.1778)
							(mid 0.249642 -0.249642)
							(end 0.1778 -0.2794)
						)
					)
					(width 0)
					(fill yes)
				)
			)
		)
		(pad "2" smd custom
			(at 0 0.4445)
			(size 0.1397 0.1397)
			(layers "F.Cu" "F.Mask" "F.Paste")
			(net "GND")
			(options
				(clearance outline)
				(anchor circle)
			)
			(primitives
				(gr_poly
					(pts
						(arc
							(start -0.1778 -0.2794)
							(mid -0.249642 -0.249642)
							(end -0.2794 -0.1778)
						)
						(arc
							(start -0.2794 0.1778)
							(mid -0.249642 0.249642)
							(end -0.1778 0.2794)
						)
						(arc
							(start 0.1778 0.2794)
							(mid 0.249642 0.249642)
							(end 0.2794 0.1778)
						)
						(arc
							(start 0.2794 -0.1778)
							(mid 0.249642 -0.249642)
							(end 0.1778 -0.2794)
						)
					)
					(width 0)
					(fill yes)
				)
			)
		)
	)
	(footprint ""
		(layer "F.Cu")
		(at 24.5618 -173.2026 -90)
		(property "Reference" "R617"
			(at 0 0 270)
			(layer "F.SilkS")
			(hide yes)
			(effects
				(font
					(size 1.27 1.27)
				)
			)
		)
		(property "Value" "27KR2F-L-GP"
			(at 0.064008 -3.993896 270)
			(unlocked yes)
			(layer "F.Fab")
			(hide yes)
			(effects
				(font
					(size 1.016 1.016)
					(thickness 0.1524)
				)
			)
		)
		(property "Device Type" "R402H16"
			(at 0.064008 -5.517896 270)
			(unlocked yes)
			(layer "F.Fab")
			(hide yes)
			(effects
				(font
					(size 1.016 1.016)
					(thickness 0.1524)
				)
			)
		)
		(duplicate_pad_numbers_are_jumpers no)
		(fp_line
			(start -0.508 -0.9398)
			(end -0.508 0.9398)
			(stroke
				(width 0.1524)
				(type default)
			)
			(layer "F.SilkS")
		)
		(fp_line
			(start 0.508 -0.9398)
			(end -0.508 -0.9398)
			(stroke
				(width 0.1524)
				(type default)
			)
			(layer "F.SilkS")
		)
		(fp_rect
			(start -0.508 0.9398)
			(end 0.508 -0.9398)
			(stroke
				(width 0)
				(type default)
			)
			(fill no)
			(layer "F.CrtYd")
		)
		(fp_rect
			(start -0.508 0.9398)
			(end 0.508 -0.9398)
			(stroke
				(width 0)
				(type default)
			)
			(fill no)
			(layer "F.Fab")
		)
		(pad "1" smd custom
			(at 0 -0.4445 270)
			(size 0.1397 0.1397)
			(layers "F.Cu" "F.Mask" "F.Paste")
			(net "PCIE_MATED#_A")
			(options
				(clearance outline)
				(anchor circle)
			)
			(primitives
				(gr_poly
					(pts
						(arc
							(start -0.1778 -0.2794)
							(mid -0.249642 -0.249642)
							(end -0.2794 -0.1778)
						)
						(arc
							(start -0.2794 0.1778)
							(mid -0.249642 0.249642)
							(end -0.1778 0.2794)
						)
						(arc
							(start 0.1778 0.2794)
							(mid 0.249642 0.249642)
							(end 0.2794 0.1778)
						)
						(arc
							(start 0.2794 -0.1778)
							(mid 0.249642 -0.249642)
							(end 0.1778 -0.2794)
						)
					)
					(width 0)
					(fill yes)
				)
			)
		)
		(pad "2" smd custom
			(at 0 0.4445 270)
			(size 0.1397 0.1397)
			(layers "F.Cu" "F.Mask" "F.Paste")
			(net "P12V_PCIE")
			(options
				(clearance outline)
				(anchor circle)
			)
			(primitives
				(gr_poly
					(pts
						(arc
							(start -0.1778 -0.2794)
							(mid -0.249642 -0.249642)
							(end -0.2794 -0.1778)
						)
						(arc
							(start -0.2794 0.1778)
							(mid -0.249642 0.249642)
							(end -0.1778 0.2794)
						)
						(arc
							(start 0.1778 0.2794)
							(mid 0.249642 0.249642)
							(end 0.2794 0.1778)
						)
						(arc
							(start 0.2794 -0.1778)
							(mid 0.249642 -0.249642)
							(end 0.1778 -0.2794)
						)
					)
					(width 0)
					(fill yes)
				)
			)
		)
	)
)
